(kicad_pcb
	(version 20241229)
	(generator "pcbnew")
	(generator_version "9.0")
	(general
		(thickness 1.62)
		(legacy_teardrops no)
	)
	(paper "A4")
	(title_block
		(title "OCuLink to 10GbE adapter")
		(date "2026-02-23")
		(rev "1.1.0")
		(company "Antmicro Ltd")
		(comment 1 "www.antmicro.com")
		(comment 9 "footprints 292-296 of 510")
	)
	(layers
		(0 "F.Cu" signal)
		(4 "In1.Cu" signal)
		(6 "In2.Cu" signal)
		(8 "In3.Cu" signal)
		(10 "In4.Cu" signal)
		(12 "In5.Cu" signal)
		(14 "In6.Cu" signal)
		(2 "B.Cu" signal)
		(9 "F.Adhes" user "F.Adhesive")
		(11 "B.Adhes" user "B.Adhesive")
		(13 "F.Paste" user)
		(15 "B.Paste" user)
		(5 "F.SilkS" user "F.Silkscreen")
		(7 "B.SilkS" user "B.Silkscreen")
		(1 "F.Mask" user)
		(3 "B.Mask" user)
		(17 "Dwgs.User" user "User.Drawings")
		(19 "Cmts.User" user "User.Comments")
		(21 "Eco1.User" user "User.Eco1")
		(23 "Eco2.User" user "User.Eco2")
		(25 "Edge.Cuts" user)
		(27 "Margin" user)
		(31 "F.CrtYd" user "F.Courtyard")
		(29 "B.CrtYd" user "B.Courtyard")
		(35 "F.Fab" user)
		(33 "B.Fab" user)
	)
	(footprint "antmicro-footprints:Tag-Connect_TC2050-IDC-NL_2x5_P1.27mm"
		(layer "B.Cu")
		(at 55.7 74.35 180)
		(property "Reference" "J10"
			(at -0.3 2.35 0)
			(layer "B.SilkS")
			(effects
				(font
					(size 0.7 0.7)
					(thickness 0.15)
				)
				(justify left bottom mirror)
			)
		)
		(property "Value" "Tag-Connect_TC2050-IDC-NL_2x5_P1.27mm"
			(at 0 -4.4 0)
			(layer "B.Fab")
			(hide yes)
			(effects
				(font
					(size 0.7 0.7)
					(thickness 0.15)
				)
				(justify left bottom mirror)
			)
		)
		(property "Datasheet" "https://www.tag-connect.com/wp-content/uploads/bsk-pdf-manager/TC2050-IDC-NL_Datasheet_8.pdf"
			(at 0 0 0)
			(layer "B.Fab")
			(hide yes)
			(effects
				(font
					(size 1.27 1.27)
					(thickness 0.15)
				)
				(justify mirror)
			)
		)
		(property "Description" "Tag Connect 2x5 1.27mm terminal"
			(at 0 0 0)
			(layer "B.Fab")
			(hide yes)
			(effects
				(font
					(size 1.27 1.27)
					(thickness 0.15)
				)
				(justify mirror)
			)
		)
		(property "MPN" "TC2050-IDC-NL"
			(at 0 0 180)
			(unlocked yes)
			(layer "B.Fab")
			(hide yes)
			(effects
				(font
					(size 1 1)
					(thickness 0.15)
				)
				(justify mirror)
			)
		)
		(property "Manufacturer" "Tag Connect"
			(at 0 0 180)
			(unlocked yes)
			(layer "B.Fab")
			(hide yes)
			(effects
				(font
					(size 1 1)
					(thickness 0.15)
				)
				(justify mirror)
			)
		)
		(property "Author" "Antmicro"
			(at 0 0 180)
			(unlocked yes)
			(layer "B.Fab")
			(hide yes)
			(effects
				(font
					(size 1 1)
					(thickness 0.15)
				)
				(justify mirror)
			)
		)
		(property "License" "Apache-2.0"
			(at 0 0 180)
			(unlocked yes)
			(layer "B.Fab")
			(hide yes)
			(effects
				(font
					(size 1 1)
					(thickness 0.15)
				)
				(justify mirror)
			)
		)
		(sheetname "/Flash memory/")
		(sheetfile "flash-memory.kicad_sch")
		(attr exclude_from_pos_files exclude_from_bom dnp)
		(fp_line
			(start 5.1 1.7)
			(end 5.1 -1.7)
			(stroke
				(width 0.15)
				(type solid)
			)
			(layer "B.SilkS")
		)
		(fp_line
			(start 4.7 2.05)
			(end 5.1 1.7)
			(stroke
				(width 0.15)
				(type solid)
			)
			(layer "B.SilkS")
		)
		(fp_line
			(start 4.7 -2.049)
			(end 5.1 -1.7)
			(stroke
				(width 0.15)
				(type solid)
			)
			(layer "B.SilkS")
		)
		(fp_line
			(start 4.7 -2.049)
			(end -2.3 -2.049)
			(stroke
				(width 0.15)
				(type solid)
			)
			(layer "B.SilkS")
		)
		(fp_line
			(start -2.2 2.05)
			(end 4.7 2.05)
			(stroke
				(width 0.15)
				(type solid)
			)
			(layer "B.SilkS")
		)
		(fp_line
			(start -2.3 -2.049)
			(end -5.08 -0.8)
			(stroke
				(width 0.15)
				(type solid)
			)
			(layer "B.SilkS")
		)
		(fp_line
			(start -3.101 -1.269)
			(end -3.101 -0.4)
			(stroke
				(width 0.15)
				(type solid)
			)
			(layer "B.SilkS")
		)
		(fp_line
			(start -5.08 0.9)
			(end -2.2 2.05)
			(stroke
				(width 0.15)
				(type solid)
			)
			(layer "B.SilkS")
		)
		(fp_line
			(start -5.08 -0.8)
			(end -5.08 0.9)
			(stroke
				(width 0.15)
				(type solid)
			)
			(layer "B.SilkS")
		)
		(fp_line
			(start 5.32 1.8)
			(end 5.32 -1.8)
			(stroke
				(width 0.05)
				(type solid)
			)
			(layer "B.CrtYd")
		)
		(fp_line
			(start 4.8 2.3)
			(end 5.32 1.8)
			(stroke
				(width 0.05)
				(type solid)
			)
			(layer "B.CrtYd")
		)
		(fp_line
			(start 4.8 -2.29)
			(end 5.32 -1.8)
			(stroke
				(width 0.05)
				(type solid)
			)
			(layer "B.CrtYd")
		)
		(fp_line
			(start 4.8 -2.29)
			(end -2.4 -2.29)
			(stroke
				(width 0.05)
				(type solid)
			)
			(layer "B.CrtYd")
		)
		(fp_line
			(start -2.3 2.3)
			(end 4.8 2.3)
			(stroke
				(width 0.05)
				(type solid)
			)
			(layer "B.CrtYd")
		)
		(fp_line
			(start -2.4 -2.29)
			(end -5.33 -1)
			(stroke
				(width 0.05)
				(type solid)
			)
			(layer "B.CrtYd")
		)
		(fp_line
			(start -5.33 1.1)
			(end -2.3 2.3)
			(stroke
				(width 0.05)
				(type solid)
			)
			(layer "B.CrtYd")
		)
		(fp_line
			(start -5.33 -1)
			(end -5.33 1.1)
			(stroke
				(width 0.05)
				(type solid)
			)
			(layer "B.CrtYd")
		)
		(pad "" np_thru_hole circle
			(at -3.81 0 180)
			(size 0.9906 0.9906)
			(drill 0.9906)
			(layers "*.Cu" "*.Mask")
		)
		(pad "" np_thru_hole circle
			(at 3.809 -1.015 180)
			(size 0.9906 0.9906)
			(drill 0.9906)
			(layers "*.Cu" "*.Mask")
		)
		(pad "" np_thru_hole circle
			(at 3.809 1.016 180)
			(size 0.9906 0.9906)
			(drill 0.9906)
			(layers "*.Cu" "*.Mask")
		)
		(pad "1" connect circle
			(at -2.54 -0.634 180)
			(size 0.7874 0.7874)
			(layers "B.Cu" "B.Mask")
			(net 110 "/Flash memory/+3V3_FLASH")
			(pinfunction "3V3")
			(pintype "passive")
		)
		(pad "2" connect circle
			(at -1.27 -0.634 180)
			(size 0.7874 0.7874)
			(layers "B.Cu" "B.Mask")
			(net 105 "/Flash memory/FLASH.~{CE}")
			(pinfunction "SPI_CS")
			(pintype "passive")
		)
		(pad "3" connect circle
			(at 0 -0.634 180)
			(size 0.7874 0.7874)
			(layers "B.Cu" "B.Mask")
			(net 28 "GND")
			(pinfunction "GND")
			(pintype "passive")
		)
		(pad "4" connect circle
			(at 1.269 -0.634 180)
			(size 0.7874 0.7874)
			(layers "B.Cu" "B.Mask")
			(net 106 "/Flash memory/FLASH.CLK")
			(pinfunction "SPI_SCK")
			(pintype "passive")
		)
		(pad "5" connect circle
			(at 2.539 -0.634 180)
			(size 0.7874 0.7874)
			(layers "B.Cu" "B.Mask")
			(net 28 "GND")
			(pinfunction "GND")
			(pintype "passive")
		)
		(pad "6" connect circle
			(at 2.539 0.635 180)
			(size 0.7874 0.7874)
			(layers "B.Cu" "B.Mask")
			(net 140 "/Flash memory/FLASH.MISO")
			(pinfunction "SPI_MISO")
			(pintype "passive")
		)
		(pad "7" connect circle
			(at 1.269 0.635 180)
			(size 0.7874 0.7874)
			(layers "B.Cu" "B.Mask")
			(net 91 "unconnected-(J10-Pad7)")
			(pinfunction "NC")
			(pintype "passive")
		)
		(pad "8" connect circle
			(at 0 0.635 180)
			(size 0.7874 0.7874)
			(layers "B.Cu" "B.Mask")
			(net 139 "/Flash memory/FLASH.MOSI")
			(pinfunction "SPI_MOSI")
			(pintype "passive")
		)
		(pad "9" connect circle
			(at -1.27 0.635 180)
			(size 0.7874 0.7874)
			(layers "B.Cu" "B.Mask")
			(net 28 "GND")
			(pinfunction "GND")
			(pintype "passive")
		)
		(pad "10" connect circle
			(at -2.54 0.635 180)
			(size 0.7874 0.7874)
			(layers "B.Cu" "B.Mask")
			(net 111 "unconnected-(J10-Pad10)")
			(pinfunction "SPI_NC")
			(pintype "passive+no_connect")
		)
	)
	(footprint "antmicro-footprints:R_0402_1005Metric"
		(layer "B.Cu")
		(at 110.49 86.76 90)
		(descr "Resistor SMD 0402")
		(tags "resistor SMD 0402")
		(property "Reference" "R130"
			(at 0.81 -0.31 90)
			(layer "B.SilkS")
			(effects
				(font
					(size 0.7 0.7)
					(thickness 0.15)
				)
				(justify right top mirror)
			)
		)
		(property "Value" "R_1k_0402"
			(at -1.011843 -1.772046 90)
			(layer "B.Fab")
			(hide yes)
			(effects
				(font
					(size 0.7 0.7)
					(thickness 0.15)
				)
				(justify right top mirror)
			)
		)
		(property "Datasheet" "https://www.bourns.com/docs/product-datasheets/cr.pdf"
			(at 0 0 90)
			(layer "B.Fab")
			(hide yes)
			(effects
				(font
					(size 1.27 1.27)
					(thickness 0.15)
				)
				(justify mirror)
			)
		)
		(property "Description" "SMD Chip Resistor, 1 kohm, ± 1%, 63 mW, 0402 [1005 Metric], Thick Film, General Purpose"
			(at 0 0 90)
			(layer "B.Fab")
			(hide yes)
			(effects
				(font
					(size 1.27 1.27)
					(thickness 0.15)
				)
				(justify mirror)
			)
		)
		(property "MPN" "CR0402-FX-1001GLF"
			(at 0 0 90)
			(unlocked yes)
			(layer "B.Fab")
			(hide yes)
			(effects
				(font
					(size 1 1)
					(thickness 0.15)
				)
				(justify mirror)
			)
		)
		(property "Manufacturer" "Bourns"
			(at 0 0 90)
			(unlocked yes)
			(layer "B.Fab")
			(hide yes)
			(effects
				(font
					(size 1 1)
					(thickness 0.15)
				)
				(justify mirror)
			)
		)
		(property "License" "Apache-2.0"
			(at 0 0 90)
			(unlocked yes)
			(layer "B.Fab")
			(hide yes)
			(effects
				(font
					(size 1 1)
					(thickness 0.15)
				)
				(justify mirror)
			)
		)
		(property "Author" "Antmicro"
			(at 0 0 90)
			(unlocked yes)
			(layer "B.Fab")
			(hide yes)
			(effects
				(font
					(size 1 1)
					(thickness 0.15)
				)
				(justify mirror)
			)
		)
		(property "Val" "1k"
			(at 0 0 90)
			(unlocked yes)
			(layer "B.Fab")
			(hide yes)
			(effects
				(font
					(size 1 1)
					(thickness 0.15)
				)
				(justify mirror)
			)
		)
		(property "Tolerance" "1%"
			(at 0 0 90)
			(unlocked yes)
			(layer "B.Fab")
			(hide yes)
			(effects
				(font
					(size 1 1)
					(thickness 0.15)
				)
				(justify mirror)
			)
		)
		(sheetname "/X710-AT2 RSVD/")
		(sheetfile "x710-at2-rsvd.kicad_sch")
		(attr smd)
		(fp_rect
			(start -0.925 0.47)
			(end 0.925 -0.47)
			(stroke
				(width 0.05)
				(type default)
			)
			(fill no)
			(layer "B.CrtYd")
		)
		(fp_rect
			(start -0.5 0.25)
			(end 0.5 -0.25)
			(stroke
				(width 0.15)
				(type solid)
			)
			(fill no)
			(layer "B.Fab")
		)
		(pad "1" smd roundrect
			(at -0.48 0 90)
			(size 0.59 0.64)
			(layers "B.Cu" "B.Mask" "B.Paste")
			(roundrect_rratio 0.25)
			(net 121 "/X710-AT2 RSVD/DEBUG_Y16")
			(pintype "passive")
		)
		(pad "2" smd roundrect
			(at 0.48 0 90)
			(size 0.59 0.64)
			(layers "B.Cu" "B.Mask" "B.Paste")
			(roundrect_rratio 0.25)
			(net 114 "/X710-AT2 RSVD/DEBUG_EN")
			(pintype "passive")
		)
	)
	(footprint "antmicro-footprints:R_0402_1005Metric"
		(layer "B.Cu")
		(at 96.95 96.5 90)
		(descr "Resistor SMD 0402")
		(tags "resistor SMD 0402")
		(property "Reference" "R108"
			(at -1.15 3.3 90)
			(layer "B.SilkS")
			(effects
				(font
					(size 0.7 0.7)
					(thickness 0.15)
				)
				(justify right bottom mirror)
			)
		)
		(property "Value" "R_100R_0402"
			(at -1.011843 -1.772046 90)
			(layer "B.Fab")
			(hide yes)
			(effects
				(font
					(size 0.7 0.7)
					(thickness 0.15)
				)
				(justify right top mirror)
			)
		)
		(property "Datasheet" "https://www.bourns.com/docs/product-datasheets/cr.pdf"
			(at 0 0 90)
			(layer "B.Fab")
			(hide yes)
			(effects
				(font
					(size 1.27 1.27)
					(thickness 0.15)
				)
				(justify mirror)
			)
		)
		(property "Description" "SMD Chip Resistor, 100 ohm, ± 1%, 62.5 mW, 0402 [1005 Metric], Thick Film, General Purpose"
			(at 0 0 90)
			(layer "B.Fab")
			(hide yes)
			(effects
				(font
					(size 1.27 1.27)
					(thickness 0.15)
				)
				(justify mirror)
			)
		)
		(property "MPN" "CR0402-FX-1000GLF"
			(at 0 0 90)
			(unlocked yes)
			(layer "B.Fab")
			(hide yes)
			(effects
				(font
					(size 1 1)
					(thickness 0.15)
				)
				(justify mirror)
			)
		)
		(property "Manufacturer" "Bourns"
			(at 0 0 90)
			(unlocked yes)
			(layer "B.Fab")
			(hide yes)
			(effects
				(font
					(size 1 1)
					(thickness 0.15)
				)
				(justify mirror)
			)
		)
		(property "License" "Apache-2.0"
			(at 0 0 90)
			(unlocked yes)
			(layer "B.Fab")
			(hide yes)
			(effects
				(font
					(size 1 1)
					(thickness 0.15)
				)
				(justify mirror)
			)
		)
		(property "Author" "Antmicro"
			(at 0 0 90)
			(unlocked yes)
			(layer "B.Fab")
			(hide yes)
			(effects
				(font
					(size 1 1)
					(thickness 0.15)
				)
				(justify mirror)
			)
		)
		(property "Val" "100R"
			(at 0 0 90)
			(unlocked yes)
			(layer "B.Fab")
			(hide yes)
			(effects
				(font
					(size 1 1)
					(thickness 0.15)
				)
				(justify mirror)
			)
		)
		(property "Tolerance" "1%"
			(at 0 0 90)
			(unlocked yes)
			(layer "B.Fab")
			(hide yes)
			(effects
				(font
					(size 1 1)
					(thickness 0.15)
				)
				(justify mirror)
			)
		)
		(sheetname "/X710-AT2 Misc/")
		(sheetfile "x710-at2-mics.kicad_sch")
		(attr smd exclude_from_pos_files exclude_from_bom dnp)
		(fp_rect
			(start -0.925 0.47)
			(end 0.925 -0.47)
			(stroke
				(width 0.05)
				(type default)
			)
			(fill no)
			(layer "B.CrtYd")
		)
		(fp_rect
			(start -0.5 0.25)
			(end 0.5 -0.25)
			(stroke
				(width 0.15)
				(type solid)
			)
			(fill no)
			(layer "B.Fab")
		)
		(pad "1" smd roundrect
			(at -0.48 0 90)
			(size 0.59 0.64)
			(layers "B.Cu" "B.Mask" "B.Paste")
			(roundrect_rratio 0.25)
			(net 28 "GND")
			(pintype "passive")
		)
		(pad "2" smd roundrect
			(at 0.48 0 90)
			(size 0.59 0.64)
			(layers "B.Cu" "B.Mask" "B.Paste")
			(roundrect_rratio 0.25)
			(net 289 "/X710-AT2 Misc/~{PCI_DIS}")
			(pintype "passive")
		)
	)
	(footprint "antmicro-footprints:TP_SMD_0.75mm"
		(layer "B.Cu")
		(at 103.55 105.7 90)
		(property "Reference" "TP8"
			(at 0.565351 0.658866 180)
			(layer "B.SilkS")
			(effects
				(font
					(size 0.7 0.7)
					(thickness 0.15)
				)
				(justify right top mirror)
			)
		)
		(property "Value" "TP_0.75mm_SMD"
			(at 0 -1.2 90)
			(layer "B.Fab")
			(hide yes)
			(effects
				(font
					(size 0.7 0.7)
					(thickness 0.15)
				)
				(justify right top mirror)
			)
		)
		(property "Description" "SMT test point"
			(at 0 0 90)
			(layer "B.Fab")
			(hide yes)
			(effects
				(font
					(size 1.27 1.27)
					(thickness 0.15)
				)
				(justify mirror)
			)
		)
		(property "MPN" ""
			(at 0 0 90)
			(unlocked yes)
			(layer "B.Fab")
			(hide yes)
			(effects
				(font
					(size 1 1)
					(thickness 0.15)
				)
				(justify mirror)
			)
		)
		(property "Manufacturer" ""
			(at 0 0 90)
			(unlocked yes)
			(layer "B.Fab")
			(hide yes)
			(effects
				(font
					(size 1 1)
					(thickness 0.15)
				)
				(justify mirror)
			)
		)
		(property "Author" "Antmicro"
			(at 0 0 90)
			(unlocked yes)
			(layer "B.Fab")
			(hide yes)
			(effects
				(font
					(size 1 1)
					(thickness 0.15)
				)
				(justify mirror)
			)
		)
		(property "License" "Apache-2.0"
			(at 0 0 90)
			(unlocked yes)
			(layer "B.Fab")
			(hide yes)
			(effects
				(font
					(size 1 1)
					(thickness 0.15)
				)
				(justify mirror)
			)
		)
		(sheetname "/X710-AT2 Misc/")
		(sheetfile "x710-at2-mics.kicad_sch")
		(attr exclude_from_pos_files exclude_from_bom)
		(fp_circle
			(center 0 0)
			(end 0.475 0)
			(stroke
				(width 0.05)
				(type default)
			)
			(fill no)
			(layer "B.CrtYd")
		)
		(pad "1" smd circle
			(at 0 0 90)
			(size 0.75 0.75)
			(layers "B.Cu" "B.Mask")
			(net 361 "/X710-AT2 Misc/NCSI.TXD_1")
			(pinfunction "1")
			(pintype "passive")
		)
	)
	(footprint "antmicro-footprints:C_0402_1005Metric"
		(layer "B.Cu")
		(at 78.44 105.08 90)
		(descr "Capacitor SMD 0402")
		(tags "capacitor SMD 0402")
		(property "Reference" "C82"
			(at -11.81 -0.04 90)
			(layer "B.SilkS")
			(effects
				(font
					(size 0.7 0.7)
					(thickness 0.15)
				)
				(justify right top mirror)
			)
		)
		(property "Value" "C_1u_25V_0402"
			(at -1.022927 -2.155213 90)
			(layer "B.Fab")
			(hide yes)
			(effects
				(font
					(size 0.7 0.7)
					(thickness 0.15)
				)
				(justify right top mirror)
			)
		)
		(property "Datasheet" "https://www.murata.com/products/productdetail?partno=GRM155R61E105KE11%23"
			(at 0 0 90)
			(layer "B.Fab")
			(hide yes)
			(effects
				(font
					(size 1.27 1.27)
					(thickness 0.15)
				)
				(justify mirror)
			)
		)
		(property "Description" "SMD Multilayer Ceramic Capacitor, 1 µF, 25 V, 0402 [1005 Metric], ± 10%, X5R, GRM Series"
			(at 0 0 90)
			(layer "B.Fab")
			(hide yes)
			(effects
				(font
					(size 1.27 1.27)
					(thickness 0.15)
				)
				(justify mirror)
			)
		)
		(property "MPN" "GRM155R61E105KE11J"
			(at 0 0 90)
			(unlocked yes)
			(layer "B.Fab")
			(hide yes)
			(effects
				(font
					(size 1 1)
					(thickness 0.15)
				)
				(justify mirror)
			)
		)
		(property "Manufacturer" "Murata"
			(at 0 0 90)
			(unlocked yes)
			(layer "B.Fab")
			(hide yes)
			(effects
				(font
					(size 1 1)
					(thickness 0.15)
				)
				(justify mirror)
			)
		)
		(property "License" "Apache-2.0"
			(at 0 0 90)
			(unlocked yes)
			(layer "B.Fab")
			(hide yes)
			(effects
				(font
					(size 1 1)
					(thickness 0.15)
				)
				(justify mirror)
			)
		)
		(property "Author" "Antmicro"
			(at 0 0 90)
			(unlocked yes)
			(layer "B.Fab")
			(hide yes)
			(effects
				(font
					(size 1 1)
					(thickness 0.15)
				)
				(justify mirror)
			)
		)
		(property "Val" "1u"
			(at 0 0 90)
			(unlocked yes)
			(layer "B.Fab")
			(hide yes)
			(effects
				(font
					(size 1 1)
					(thickness 0.15)
				)
				(justify mirror)
			)
		)
		(property "Voltage" "25V"
			(at 0 0 90)
			(unlocked yes)
			(layer "B.Fab")
			(hide yes)
			(effects
				(font
					(size 1 1)
					(thickness 0.15)
				)
				(justify mirror)
			)
		)
		(property "Dielectric" "X5R"
			(at 0 0 90)
			(unlocked yes)
			(layer "B.Fab")
			(hide yes)
			(effects
				(font
					(size 1 1)
					(thickness 0.15)
				)
				(justify mirror)
			)
		)
		(sheetname "/X710-AT2 power/")
		(sheetfile "x710-at2-power.kicad_sch")
		(attr smd)
		(fp_rect
			(start -0.925 0.47)
			(end 0.925 -0.47)
			(stroke
				(width 0.05)
				(type default)
			)
			(fill no)
			(layer "B.CrtYd")
		)
		(fp_line
			(start 0.504 -0.248)
			(end -0.494 -0.248)
			(stroke
				(width 0.15)
				(type solid)
			)
			(layer "B.Fab")
		)
		(fp_line
			(start -0.494 -0.248)
			(end -0.494 0.25)
			(stroke
				(width 0.15)
				(type solid)
			)
			(layer "B.Fab")
		)
		(fp_line
			(start 0.504 0.25)
			(end 0.504 -0.248)
			(stroke
				(width 0.15)
				(type solid)
			)
			(layer "B.Fab")
		)
		(fp_line
			(start -0.494 0.25)
			(end 0.504 0.25)
			(stroke
				(width 0.15)
				(type solid)
			)
			(layer "B.Fab")
		)
		(pad "1" smd roundrect
			(at -0.48 0 90)
			(size 0.59 0.64)
			(layers "B.Cu" "B.Mask" "B.Paste")
			(roundrect_rratio 0.25)
			(net 28 "GND")
			(pintype "passive")
		)
		(pad "2" smd roundrect
			(at 0.48 0 90)
			(size 0.59 0.64)
			(layers "B.Cu" "B.Mask" "B.Paste")
			(roundrect_rratio 0.25)
			(net 6 "DVDD")
			(pintype "passive")
		)
	)
)
